# S9S_MB_2U (Grand Teton) — schematic netlist excerpt (pin names and nets, part order shuffled) for the footprints in the layout excerpt that follows; sources: Cadence DE-HDL packaged netlist, KiCad conversion of 03242023_DA0F0TMBIJ0_F0T_Motherboard_J_brd_V01_OCP.brd

R1695  Q_RES  0 5% EMPTY  pkg 0402LF  page 244 : A = PWRGD_DSW_PWROK ; B = RST_RSMRST_PCH_N
PR3967  Q_RES  10 1% CHIP  pkg 0402LF  page 192 : A = P3V3_AUX ; B = P3V3_E1S_VCC_0

(kicad_pcb
	(version 20260206)
	(generator "pcbnew")
	(generator_version "10.0")
	(general
		(thickness 1.6)
		(legacy_teardrops no)
	)
	(paper "A4")
	(title_block
		(title "03242023_DA0F0TMBIJ0_F0T_Motherboard_J_brd_V01_OCP.brd")
		(comment 1 "Grand Teton / footprints 339-340 of 6105")
	)
	(layers
		(0 "F.Cu" signal "TOP")
		(4 "In1.Cu" signal "GND")
		(6 "In2.Cu" signal "IN1")
		(8 "In3.Cu" signal "GND1")
		(10 "In4.Cu" signal "IN2")
		(12 "In5.Cu" signal "GND2")
		(14 "In6.Cu" signal "IN3")
		(16 "In7.Cu" signal "GND3")
		(18 "In8.Cu" signal "VCC")
		(20 "In9.Cu" signal "VCC1")
		(22 "In10.Cu" signal "GND4")
		(24 "In11.Cu" signal "IN4")
		(26 "In12.Cu" signal "GND5")
		(28 "In13.Cu" signal "IN5")
		(30 "In14.Cu" signal "GND6")
		(32 "In15.Cu" signal "IN6")
		(34 "In16.Cu" signal "GND7")
		(2 "B.Cu" signal "BOTTOM")
		(9 "F.Adhes" user "F.Adhesive")
		(11 "B.Adhes" user "B.Adhesive")
		(13 "F.Paste" user "Package Geometry/Pastemask Top")
		(15 "B.Paste" user "Package Geometry/Pastemask Bottom")
		(5 "F.SilkS" user "Ref Des/Silkscreen Top")
		(7 "B.SilkS" user "Ref Des/Silkscreen Bottom")
		(1 "F.Mask" user "Board Geometry/Soldermask Top")
		(3 "B.Mask" user "Board Geometry/Soldermask Bottom")
		(17 "Dwgs.User" user "User.Drawings")
		(19 "Cmts.User" user "User.Comments")
		(21 "Eco1.User" user "User.Eco1")
		(23 "Eco2.User" user "User.Eco2")
		(25 "Edge.Cuts" user "Board Geometry/Outline")
		(27 "Margin" user)
		(31 "F.CrtYd" user "Package Geometry/Place Bound Top")
		(29 "B.CrtYd" user "Package Geometry/Place Bound Bottom")
		(35 "F.Fab" user "Ref Des/Assembly Top")
		(33 "B.Fab" user "Ref Des/Assembly Bottom")
	)
	(footprint ""
		(layer "F.Cu")
		(at 209.74558 -127.528828)
		(property "Reference" "R1695"
			(at 0 0 0)
			(layer "F.SilkS")
			(hide yes)
			(effects
				(font
					(size 1.27 1.27)
				)
			)
		)
		(property "Value" ""
			(at 0 0 0)
			(layer "F.Fab")
			(effects
				(font
					(size 1.27 1.27)
				)
			)
		)
		(duplicate_pad_numbers_are_jumpers no)
		(fp_line
			(start -0.7874 -0.4064)
			(end 0.7874 -0.4064)
			(stroke
				(width 0.1524)
				(type default)
			)
			(layer "F.SilkS")
		)
		(fp_line
			(start -0.7874 0.4064)
			(end -0.7874 -0.4064)
			(stroke
				(width 0.1524)
				(type default)
			)
			(layer "F.SilkS")
		)
		(fp_line
			(start 0.7874 -0.4064)
			(end 0.7874 0.4064)
			(stroke
				(width 0.1524)
				(type default)
			)
			(layer "F.SilkS")
		)
		(fp_line
			(start 0.7874 0.4064)
			(end -0.7874 0.4064)
			(stroke
				(width 0.1524)
				(type default)
			)
			(layer "F.SilkS")
		)
		(fp_line
			(start -0.67945 -0.305054)
			(end -0.12065 -0.305054)
			(stroke
				(width 0.1)
				(type default)
			)
			(layer "F.Fab")
		)
		(fp_line
			(start -0.67945 0.3048)
			(end -0.67945 -0.305054)
			(stroke
				(width 0.1)
				(type default)
			)
			(layer "F.Fab")
		)
		(fp_line
			(start -0.12065 -0.305054)
			(end -0.12065 -0.2794)
			(stroke
				(width 0.1)
				(type default)
			)
			(layer "F.Fab")
		)
		(fp_line
			(start -0.12065 -0.2794)
			(end 0.12065 -0.2794)
			(stroke
				(width 0.1)
				(type default)
			)
			(layer "F.Fab")
		)
		(fp_line
			(start -0.12065 0.2794)
			(end -0.12065 0.3048)
			(stroke
				(width 0.1)
				(type default)
			)
			(layer "F.Fab")
		)
		(fp_line
			(start -0.12065 0.3048)
			(end -0.67945 0.3048)
			(stroke
				(width 0.1)
				(type default)
			)
			(layer "F.Fab")
		)
		(fp_line
			(start 0.120396 0.2794)
			(end -0.12065 0.2794)
			(stroke
				(width 0.1)
				(type default)
			)
			(layer "F.Fab")
		)
		(fp_line
			(start 0.120396 0.3048)
			(end 0.120396 0.2794)
			(stroke
				(width 0.1)
				(type default)
			)
			(layer "F.Fab")
		)
		(fp_line
			(start 0.12065 -0.3048)
			(end 0.67945 -0.3048)
			(stroke
				(width 0.1)
				(type default)
			)
			(layer "F.Fab")
		)
		(fp_line
			(start 0.12065 -0.2794)
			(end 0.12065 -0.3048)
			(stroke
				(width 0.1)
				(type default)
			)
			(layer "F.Fab")
		)
		(fp_line
			(start 0.67945 -0.3048)
			(end 0.67945 0.3048)
			(stroke
				(width 0.1)
				(type default)
			)
			(layer "F.Fab")
		)
		(fp_line
			(start 0.67945 0.3048)
			(end 0.120396 0.3048)
			(stroke
				(width 0.1)
				(type default)
			)
			(layer "F.Fab")
		)
		(pad "1" smd circle
			(at -0.40005 0)
			(size 0 0)
			(layers "F.Cu" "F.Mask" "F.Paste")
			(net "PWRGD_DSW_PWROK")
		)
		(pad "2" smd circle
			(at 0.40005 0)
			(size 0 0)
			(layers "F.Cu" "F.Mask" "F.Paste")
			(net "RST_RSMRST_PCH_N")
		)
	)
	(footprint ""
		(layer "F.Cu")
		(at 220.363034 -75.02779 -90)
		(property "Reference" "PR3967"
			(at 0 0 270)
			(layer "F.SilkS")
			(hide yes)
			(effects
				(font
					(size 1.27 1.27)
				)
			)
		)
		(property "Value" ""
			(at 0 0 270)
			(layer "F.Fab")
			(effects
				(font
					(size 1.27 1.27)
				)
			)
		)
		(duplicate_pad_numbers_are_jumpers no)
		(fp_line
			(start -0.7874 0.4064)
			(end -0.7874 -0.4064)
			(stroke
				(width 0.1524)
				(type default)
			)
			(layer "F.SilkS")
		)
		(fp_line
			(start 0.7874 0.4064)
			(end -0.7874 0.4064)
			(stroke
				(width 0.1524)
				(type default)
			)
			(layer "F.SilkS")
		)
		(fp_line
			(start -0.7874 -0.4064)
			(end 0.7874 -0.4064)
			(stroke
				(width 0.1524)
				(type default)
			)
			(layer "F.SilkS")
		)
		(fp_line
			(start 0.7874 -0.4064)
			(end 0.7874 0.4064)
			(stroke
				(width 0.1524)
				(type default)
			)
			(layer "F.SilkS")
		)
		(fp_line
			(start -0.67945 0.3048)
			(end -0.67945 -0.305054)
			(stroke
				(width 0.1)
				(type default)
			)
			(layer "F.Fab")
		)
		(fp_line
			(start -0.12065 0.3048)
			(end -0.67945 0.3048)
			(stroke
				(width 0.1)
				(type default)
			)
			(layer "F.Fab")
		)
		(fp_line
			(start 0.120396 0.3048)
			(end 0.120396 0.2794)
			(stroke
				(width 0.1)
				(type default)
			)
			(layer "F.Fab")
		)
		(fp_line
			(start 0.67945 0.3048)
			(end 0.120396 0.3048)
			(stroke
				(width 0.1)
				(type default)
			)
			(layer "F.Fab")
		)
		(fp_line
			(start -0.12065 0.2794)
			(end -0.12065 0.3048)
			(stroke
				(width 0.1)
				(type default)
			)
			(layer "F.Fab")
		)
		(fp_line
			(start 0.120396 0.2794)
			(end -0.12065 0.2794)
			(stroke
				(width 0.1)
				(type default)
			)
			(layer "F.Fab")
		)
		(fp_line
			(start -0.12065 -0.2794)
			(end 0.12065 -0.2794)
			(stroke
				(width 0.1)
				(type default)
			)
			(layer "F.Fab")
		)
		(fp_line
			(start 0.12065 -0.2794)
			(end 0.12065 -0.3048)
			(stroke
				(width 0.1)
				(type default)
			)
			(layer "F.Fab")
		)
		(fp_line
			(start 0.12065 -0.3048)
			(end 0.67945 -0.3048)
			(stroke
				(width 0.1)
				(type default)
			)
			(layer "F.Fab")
		)
		(fp_line
			(start 0.67945 -0.3048)
			(end 0.67945 0.3048)
			(stroke
				(width 0.1)
				(type default)
			)
			(layer "F.Fab")
		)
		(fp_line
			(start -0.67945 -0.305054)
			(end -0.12065 -0.305054)
			(stroke
				(width 0.1)
				(type default)
			)
			(layer "F.Fab")
		)
		(fp_line
			(start -0.12065 -0.305054)
			(end -0.12065 -0.2794)
			(stroke
				(width 0.1)
				(type default)
			)
			(layer "F.Fab")
		)
		(pad "1" smd circle
			(at -0.40005 0 270)
			(size 0 0)
			(layers "F.Cu" "F.Mask" "F.Paste")
			(net "P3V3_AUX")
		)
		(pad "2" smd circle
			(at 0.40005 0 270)
			(size 0 0)
			(layers "F.Cu" "F.Mask" "F.Paste")
			(net "P3V3_E1S_VCC_0")
		)
	)
)
